(kicad_pcb
	(version 20260206)
	(generator "pcbnew")
	(generator_version "10.0")
	(general
		(thickness 1.6)
		(legacy_teardrops no)
	)
	(paper "A4")
	(title_block
		(title "Wiwynn_Tioga_Pass_MB.brd")
		(comment 1 "Tioga Pass / footprints 713-718 of 4770")
	)
	(layers
		(0 "F.Cu" signal "TOP")
		(4 "In1.Cu" signal "L2GND")
		(6 "In2.Cu" signal "L3")
		(8 "In3.Cu" signal "L4GND")
		(10 "In4.Cu" signal "L5")
		(12 "In5.Cu" signal "L6GND")
		(14 "In6.Cu" signal "L7VCC")
		(16 "In7.Cu" signal "L8VCC")
		(18 "In8.Cu" signal "L9GND")
		(20 "In9.Cu" signal "L10")
		(22 "In10.Cu" signal "L11GND")
		(24 "In11.Cu" signal "L12")
		(26 "In12.Cu" signal "L13GND")
		(2 "B.Cu" signal "BOTTOM")
		(9 "F.Adhes" user "F.Adhesive")
		(11 "B.Adhes" user "B.Adhesive")
		(13 "F.Paste" user "Package Geometry/Pastemask Top")
		(15 "B.Paste" user "Package Geometry/Pastemask Bottom")
		(5 "F.SilkS" user "Ref Des/Silkscreen Top")
		(7 "B.SilkS" user "Ref Des/Silkscreen Bottom")
		(1 "F.Mask" user "Board Geometry/Soldermask Top")
		(3 "B.Mask" user "Board Geometry/Soldermask Bottom")
		(17 "Dwgs.User" user "User.Drawings")
		(19 "Cmts.User" user "User.Comments")
		(21 "Eco1.User" user "User.Eco1")
		(23 "Eco2.User" user "User.Eco2")
		(25 "Edge.Cuts" user "Board Geometry/Outline")
		(27 "Margin" user)
		(31 "F.CrtYd" user "Package Geometry/Place Bound Top")
		(29 "B.CrtYd" user "Package Geometry/Place Bound Bottom")
		(35 "F.Fab" user "Ref Des/Assembly Top")
		(33 "B.Fab" user "Ref Des/Assembly Bottom")
	)
	(footprint ""
		(layer "F.Cu")
		(at 261.942072 -77.636116)
		(property "Reference" "C5D27"
			(at 0 0 0)
			(layer "F.SilkS")
			(hide yes)
			(effects
				(font
					(size 1.27 1.27)
				)
			)
		)
		(property "Value" ""
			(at 0 0 0)
			(layer "F.Fab")
			(effects
				(font
					(size 1.27 1.27)
				)
			)
		)
		(duplicate_pad_numbers_are_jumpers no)
		(fp_poly
			(pts
				(xy -0.4953 -0.2032) (xy 0.4953 -0.2032) (xy 0.4953 1.6002) (xy -0.4953 1.6002)
			)
			(stroke
				(width 0)
				(type default)
			)
			(fill no)
			(layer "F.CrtYd")
		)
		(fp_line
			(start -0.4953 -0.2032)
			(end 0.4953 -0.2032)
			(stroke
				(width 0.1)
				(type default)
			)
			(layer "F.Fab")
		)
		(fp_line
			(start -0.4953 1.6002)
			(end -0.4953 -0.2032)
			(stroke
				(width 0.1)
				(type default)
			)
			(layer "F.Fab")
		)
		(fp_line
			(start 0.4953 -0.2032)
			(end 0.4953 1.6002)
			(stroke
				(width 0.1)
				(type default)
			)
			(layer "F.Fab")
		)
		(fp_line
			(start 0.4953 1.6002)
			(end -0.4953 1.6002)
			(stroke
				(width 0.1)
				(type default)
			)
			(layer "F.Fab")
		)
		(pad "1" smd rect
			(at 0 0)
			(size 0.762 0.889)
			(layers "F.Cu" "F.Mask" "F.Paste")
			(net "PVCCIN_CPU0")
		)
		(pad "2" smd rect
			(at 0 1.397)
			(size 0.762 0.889)
			(layers "F.Cu" "F.Mask" "F.Paste")
			(net "GND")
		)
		(zone
			(layer "F.Cu")
			(hatch none 0.5)
			(connect_pads
				(clearance 0)
			)
			(min_thickness 0.25)
			(keepout
				(tracks not_allowed)
				(vias allowed)
				(pads allowed)
				(copperpour not_allowed)
				(footprints allowed)
			)
			(placement
				(enabled no)
				(sheetname "")
			)
			(fill
				(thermal_gap 0.5)
				(thermal_bridge_width 0.5)
				(island_removal_mode 0)
			)
			(polygon
				(pts
					(xy 261.561072 -77.191616) (xy 262.323072 -77.191616) (xy 262.323072 -76.683616) (xy 261.561072 -76.683616)
				)
			)
		)
	)
	(footprint ""
		(layer "F.Cu")
		(at 163.576 -81.788 -90)
		(property "Reference" "R4D16"
			(at 0 0 270)
			(layer "F.SilkS")
			(hide yes)
			(effects
				(font
					(size 1.27 1.27)
				)
			)
		)
		(property "Value" ""
			(at 0 0 270)
			(layer "F.Fab")
			(effects
				(font
					(size 1.27 1.27)
				)
			)
		)
		(duplicate_pad_numbers_are_jumpers no)
		(fp_poly
			(pts
				(xy -0.2794 -0.1016) (xy 0.2794 -0.1016) (xy 0.2794 0.9906) (xy -0.2794 0.9906)
			)
			(stroke
				(width 0)
				(type default)
			)
			(fill no)
			(layer "F.CrtYd")
		)
		(fp_line
			(start -0.2794 0.9906)
			(end 0.2794 0.9906)
			(stroke
				(width 0.1)
				(type default)
			)
			(layer "F.Fab")
		)
		(fp_line
			(start 0.2794 0.9906)
			(end 0.2794 -0.1016)
			(stroke
				(width 0.1)
				(type default)
			)
			(layer "F.Fab")
		)
		(fp_line
			(start -0.2794 -0.1016)
			(end -0.2794 0.9906)
			(stroke
				(width 0.1)
				(type default)
			)
			(layer "F.Fab")
		)
		(fp_line
			(start 0.2794 -0.1016)
			(end -0.2794 -0.1016)
			(stroke
				(width 0.1)
				(type default)
			)
			(layer "F.Fab")
		)
		(pad "1" smd rect
			(at 0 0 270)
			(size 0.508 0.508)
			(layers "F.Cu" "F.Mask" "F.Paste")
			(net "CLK_100M_CPU1_PE_REFCLK_R_DN")
		)
		(pad "2" smd rect
			(at 0 0.889 270)
			(size 0.508 0.508)
			(layers "F.Cu" "F.Mask" "F.Paste")
			(net "CLK_100M_CPU1_PE_REFCLK_DN")
		)
		(zone
			(layer "F.Cu")
			(hatch none 0.5)
			(connect_pads
				(clearance 0)
			)
			(min_thickness 0.25)
			(keepout
				(tracks not_allowed)
				(vias allowed)
				(pads allowed)
				(copperpour not_allowed)
				(footprints allowed)
			)
			(placement
				(enabled no)
				(sheetname "")
			)
			(fill
				(thermal_gap 0.5)
				(thermal_bridge_width 0.5)
				(island_removal_mode 0)
			)
			(polygon
				(pts
					(xy 162.941 -82.042) (xy 162.941 -81.534) (xy 163.322 -81.534) (xy 163.322 -82.042)
				)
			)
		)
		(zone
			(layer "F.Cu")
			(hatch none 0.5)
			(connect_pads
				(clearance 0)
			)
			(min_thickness 0.25)
			(keepout
				(tracks allowed)
				(vias not_allowed)
				(pads allowed)
				(copperpour not_allowed)
				(footprints allowed)
			)
			(placement
				(enabled no)
				(sheetname "")
			)
			(fill
				(thermal_gap 0.5)
				(thermal_bridge_width 0.5)
				(island_removal_mode 0)
			)
			(polygon
				(pts
					(xy 163.322 -82.042) (xy 163.322 -81.534) (xy 162.941 -81.534) (xy 162.941 -82.042)
				)
			)
		)
	)
	(footprint ""
		(layer "F.Cu")
		(at 458.39888 -26.17978 180)
		(property "Reference" "R9F30"
			(at 0 0 180)
			(layer "F.SilkS")
			(hide yes)
			(effects
				(font
					(size 1.27 1.27)
				)
			)
		)
		(property "Value" ""
			(at 0 0 180)
			(layer "F.Fab")
			(effects
				(font
					(size 1.27 1.27)
				)
			)
		)
		(duplicate_pad_numbers_are_jumpers no)
		(fp_poly
			(pts
				(xy -0.2794 -0.1016) (xy 0.2794 -0.1016) (xy 0.2794 0.9906) (xy -0.2794 0.9906)
			)
			(stroke
				(width 0)
				(type default)
			)
			(fill no)
			(layer "F.CrtYd")
		)
		(fp_line
			(start 0.2794 0.9906)
			(end 0.2794 -0.1016)
			(stroke
				(width 0.1)
				(type default)
			)
			(layer "F.Fab")
		)
		(fp_line
			(start 0.2794 -0.1016)
			(end -0.2794 -0.1016)
			(stroke
				(width 0.1)
				(type default)
			)
			(layer "F.Fab")
		)
		(fp_line
			(start -0.2794 0.9906)
			(end 0.2794 0.9906)
			(stroke
				(width 0.1)
				(type default)
			)
			(layer "F.Fab")
		)
		(fp_line
			(start -0.2794 -0.1016)
			(end -0.2794 0.9906)
			(stroke
				(width 0.1)
				(type default)
			)
			(layer "F.Fab")
		)
		(pad "1" smd rect
			(at 0 0 180)
			(size 0.508 0.508)
			(layers "F.Cu" "F.Mask" "F.Paste")
			(net "P3V3_STBY")
		)
		(pad "2" smd rect
			(at 0 0.889 180)
			(size 0.508 0.508)
			(layers "F.Cu" "F.Mask" "F.Paste")
			(net "FM_BMC_FAULT_LED_N")
		)
		(zone
			(layer "F.Cu")
			(hatch none 0.5)
			(connect_pads
				(clearance 0)
			)
			(min_thickness 0.25)
			(keepout
				(tracks not_allowed)
				(vias allowed)
				(pads allowed)
				(copperpour not_allowed)
				(footprints allowed)
			)
			(placement
				(enabled no)
				(sheetname "")
			)
			(fill
				(thermal_gap 0.5)
				(thermal_bridge_width 0.5)
				(island_removal_mode 0)
			)
			(polygon
				(pts
					(xy 458.65288 -26.81478) (xy 458.14488 -26.81478) (xy 458.14488 -26.43378) (xy 458.65288 -26.43378)
				)
			)
		)
		(zone
			(layer "F.Cu")
			(hatch none 0.5)
			(connect_pads
				(clearance 0)
			)
			(min_thickness 0.25)
			(keepout
				(tracks allowed)
				(vias not_allowed)
				(pads allowed)
				(copperpour not_allowed)
				(footprints allowed)
			)
			(placement
				(enabled no)
				(sheetname "")
			)
			(fill
				(thermal_gap 0.5)
				(thermal_bridge_width 0.5)
				(island_removal_mode 0)
			)
			(polygon
				(pts
					(xy 458.65288 -26.43378) (xy 458.14488 -26.43378) (xy 458.14488 -26.81478) (xy 458.65288 -26.81478)
				)
			)
		)
	)
	(footprint ""
		(layer "F.Cu")
		(at 132.650484 12.014454 -90)
		(property "Reference" "T1P10"
			(at 0 0 270)
			(layer "F.SilkS")
			(hide yes)
			(effects
				(font
					(size 1.27 1.27)
				)
			)
		)
		(property "Value" "*"
			(at -3.302 1.12395 270)
			(unlocked yes)
			(layer "F.Fab")
			(hide yes)
			(effects
				(font
					(size 0.889 0.889)
					(thickness 0.1524)
				)
			)
		)
		(property "Device Type" "TPAD-DIFF-4P-GP_DISCRET-GB3-TPA"
			(at -3.302 -0.40005 270)
			(unlocked yes)
			(layer "F.Fab")
			(hide yes)
			(effects
				(font
					(size 0.889 0.889)
					(thickness 0.1524)
				)
			)
		)
		(duplicate_pad_numbers_are_jumpers no)
		(fp_line
			(start -2.286 2.286)
			(end 2.286 2.286)
			(stroke
				(width 0.1524)
				(type default)
			)
			(layer "F.SilkS")
		)
		(fp_line
			(start 2.286 2.286)
			(end 2.286 -2.286)
			(stroke
				(width 0.1524)
				(type default)
			)
			(layer "F.SilkS")
		)
		(fp_line
			(start -2.286 -2.286)
			(end -2.286 2.286)
			(stroke
				(width 0.1524)
				(type default)
			)
			(layer "F.SilkS")
		)
		(fp_line
			(start 2.286 -2.286)
			(end -2.286 -2.286)
			(stroke
				(width 0.1524)
				(type default)
			)
			(layer "F.SilkS")
		)
		(fp_line
			(start -2.413 -2.413)
			(end -2.413 -1.143)
			(stroke
				(width 0.4064)
				(type default)
			)
			(layer "F.SilkS")
		)
		(fp_line
			(start -1.143 -2.413)
			(end -2.413 -2.413)
			(stroke
				(width 0.4064)
				(type default)
			)
			(layer "F.SilkS")
		)
		(fp_rect
			(start -2.54 2.54)
			(end 2.54 -2.54)
			(stroke
				(width 0)
				(type default)
			)
			(fill no)
			(layer "F.CrtYd")
		)
		(fp_rect
			(start -2.54 2.54)
			(end 2.54 -2.54)
			(stroke
				(width 0)
				(type default)
			)
			(fill no)
			(layer "F.Fab")
		)
		(pad "1" thru_hole circle
			(at -1.27 -1.27 270)
			(size 1.524 1.524)
			(drill 0.9144)
			(layers "*.Cu" "*.Mask")
			(remove_unused_layers no)
			(net "L10_73OHM_6INCH_DP")
			(clearance -0.0508)
			(thermal_gap 0.127)
			(padstack
				(mode front_inner_back)
				(layer "Inner"
					(shape circle)
					(size 1.1684 1.1684)
					(clearance 0.127)
				)
				(layer "B.Cu"
					(shape circle)
					(size 1.524 1.524)
					(clearance -0.0508)
				)
			)
		)
		(pad "2" thru_hole circle
			(at 1.27 -1.27 270)
			(size 1.524 1.524)
			(drill 0.9144)
			(layers "*.Cu" "*.Mask")
			(remove_unused_layers no)
			(net "L10_73OHM_6INCH_DN")
			(clearance -0.0508)
			(thermal_gap 0.127)
			(padstack
				(mode front_inner_back)
				(layer "Inner"
					(shape circle)
					(size 1.1684 1.1684)
					(clearance 0.127)
				)
				(layer "B.Cu"
					(shape circle)
					(size 1.524 1.524)
					(clearance -0.0508)
				)
			)
		)
		(pad "GND1" thru_hole rect
			(at -1.27 1.27 270)
			(size 1.524 1.524)
			(drill 0.9144)
			(layers "*.Cu" "*.Mask")
			(remove_unused_layers no)
			(net "GND")
			(clearance -0.0508)
			(thermal_gap 0.127)
			(padstack
				(mode front_inner_back)
				(layer "Inner"
					(shape circle)
					(size 1.1684 1.1684)
					(clearance 0.127)
				)
				(layer "B.Cu"
					(shape rect)
					(size 1.524 1.524)
					(clearance -0.0508)
				)
			)
		)
		(pad "GND2" thru_hole rect
			(at 1.27 1.27 270)
			(size 1.524 1.524)
			(drill 0.9144)
			(layers "*.Cu" "*.Mask")
			(remove_unused_layers no)
			(net "GND")
			(clearance -0.0508)
			(thermal_gap 0.127)
			(padstack
				(mode front_inner_back)
				(layer "Inner"
					(shape circle)
					(size 1.1684 1.1684)
					(clearance 0.127)
				)
				(layer "B.Cu"
					(shape rect)
					(size 1.524 1.524)
					(clearance -0.0508)
				)
			)
		)
	)
	(footprint ""
		(layer "F.Cu")
		(at 13.716 -54.917848 90)
		(property "Reference" "C1E12"
			(at 0 0 90)
			(layer "F.SilkS")
			(hide yes)
			(effects
				(font
					(size 1.27 1.27)
				)
			)
		)
		(property "Value" ""
			(at 0 0 90)
			(layer "F.Fab")
			(effects
				(font
					(size 1.27 1.27)
				)
			)
		)
		(duplicate_pad_numbers_are_jumpers no)
		(fp_rect
			(start 0.7239 -0.2159)
			(end -0.7239 1.9939)
			(stroke
				(width 0)
				(type default)
			)
			(fill no)
			(layer "F.CrtYd")
		)
		(fp_line
			(start 0.7239 -0.2159)
			(end -0.7239 -0.2159)
			(stroke
				(width 0.1)
				(type default)
			)
			(layer "F.Fab")
		)
		(fp_line
			(start -0.7239 -0.2159)
			(end -0.7239 1.9939)
			(stroke
				(width 0.1)
				(type default)
			)
			(layer "F.Fab")
		)
		(fp_line
			(start 0.7239 1.9939)
			(end 0.7239 -0.2159)
			(stroke
				(width 0.1)
				(type default)
			)
			(layer "F.Fab")
		)
		(fp_line
			(start -0.7239 1.9939)
			(end 0.7239 1.9939)
			(stroke
				(width 0.1)
				(type default)
			)
			(layer "F.Fab")
		)
		(pad "1" smd rect
			(at 0 0 90)
			(size 1.27 1.016)
			(layers "F.Cu" "F.Mask" "F.Paste")
			(net "P12V_PSU")
		)
		(pad "2" smd rect
			(at 0 1.778 90)
			(size 1.27 1.016)
			(layers "F.Cu" "F.Mask" "F.Paste")
			(net "GND")
		)
		(zone
			(layer "F.Cu")
			(hatch none 0.5)
			(connect_pads
				(clearance 0)
			)
			(min_thickness 0.25)
			(keepout
				(tracks not_allowed)
				(vias allowed)
				(pads allowed)
				(copperpour not_allowed)
				(footprints allowed)
			)
			(placement
				(enabled no)
				(sheetname "")
			)
			(fill
				(thermal_gap 0.5)
				(thermal_bridge_width 0.5)
				(island_removal_mode 0)
			)
			(polygon
				(pts
					(xy 14.224 -55.552848) (xy 14.224 -54.282848) (xy 14.986 -54.282848) (xy 14.986 -55.552848)
				)
			)
		)
	)
	(footprint ""
		(layer "F.Cu")
		(at 392.176 -67.691)
		(property "Reference" "EU7E2"
			(at 2.90195 0.67056 90)
			(unlocked yes)
			(layer "F.SilkS")
			(effects
				(font
					(size 0.7874 0.5842)
					(thickness 0.1524)
				)
				(justify left)
			)
		)
		(property "Value" ""
			(at 0 0 0)
			(layer "F.Fab")
			(effects
				(font
					(size 1.27 1.27)
				)
			)
		)
		(duplicate_pad_numbers_are_jumpers no)
		(fp_line
			(start -1.82499 -1.82499)
			(end -1.82499 -1.571498)
			(stroke
				(width 0.1524)
				(type default)
			)
			(layer "F.SilkS")
		)
		(fp_line
			(start -1.82499 1.571498)
			(end -1.82499 1.82499)
			(stroke
				(width 0.1524)
				(type default)
			)
			(layer "F.SilkS")
		)
		(fp_line
			(start -1.82499 1.82499)
			(end -1.321562 1.82499)
			(stroke
				(width 0.1524)
				(type default)
			)
			(layer "F.SilkS")
		)
		(fp_line
			(start -1.321562 -1.82499)
			(end -1.82499 -1.82499)
			(stroke
				(width 0.1524)
				(type default)
			)
			(layer "F.SilkS")
		)
		(fp_line
			(start 1.321562 1.82499)
			(end 1.82499 1.82499)
			(stroke
				(width 0.1524)
				(type default)
			)
			(layer "F.SilkS")
		)
		(fp_line
			(start 1.82499 -1.82499)
			(end 1.321562 -1.82499)
			(stroke
				(width 0.1524)
				(type default)
			)
			(layer "F.SilkS")
		)
		(fp_line
			(start 1.82499 -1.571498)
			(end 1.82499 -1.82499)
			(stroke
				(width 0.1524)
				(type default)
			)
			(layer "F.SilkS")
		)
		(fp_line
			(start 1.82499 1.82499)
			(end 1.82499 1.571498)
			(stroke
				(width 0.1524)
				(type default)
			)
			(layer "F.SilkS")
		)
		(fp_circle
			(center -1.287272 -2.56667)
			(end -1.160272 -2.56667)
			(stroke
				(width 0.254)
				(type default)
			)
			(fill no)
			(layer "F.SilkS")
		)
		(fp_poly
			(pts
				(xy -2.09169 -2.09169) (xy -2.09169 -1.32969) (xy -1.32969 -2.09169)
			)
			(stroke
				(width 0)
				(type default)
			)
			(fill yes)
			(layer "F.SilkS")
		)
		(fp_poly
			(pts
				(xy -1.0287 1.0287) (xy -1.0287 -1.0287) (xy -0.381 -1.0287) (xy -0.381 -2.1336) (xy -0.1905 -2.1336)
				(xy -0.1905 -1.397) (xy 0.1905 -1.397) (xy 0.1905 -2.1336) (xy 0.381 -2.1336) (xy 0.381 -1.0287)
				(xy 1.0287 -1.0287) (xy 1.0287 1.0287) (xy 0.381 1.0287) (xy 0.381 2.1336) (xy 0.1905 2.1336) (xy 0.1905 1.397)
				(xy -0.1905 1.397) (xy -0.1905 2.1336) (xy -0.381 2.1336) (xy -0.381 1.0287)
			)
			(stroke
				(width 0)
				(type default)
			)
			(fill yes)
			(layer "F.Paste")
		)
		(fp_rect
			(start -1.82499 1.82499)
			(end 1.82499 -1.82499)
			(stroke
				(width 0)
				(type default)
			)
			(fill no)
			(layer "F.CrtYd")
		)
		(fp_line
			(start -1.82499 -1.82499)
			(end 1.82499 -1.82499)
			(stroke
				(width 0.1)
				(type default)
			)
			(layer "F.Fab")
		)
		(fp_line
			(start -1.82499 1.82499)
			(end -1.82499 -1.82499)
			(stroke
				(width 0.1)
				(type default)
			)
			(layer "F.Fab")
		)
		(fp_line
			(start 1.82499 -1.82499)
			(end 1.82499 1.82499)
			(stroke
				(width 0.1)
				(type default)
			)
			(layer "F.Fab")
		)
		(fp_line
			(start 1.82499 1.82499)
			(end -1.82499 1.82499)
			(stroke
				(width 0.1)
				(type default)
			)
			(layer "F.Fab")
		)
		(fp_circle
			(center -1.287272 -2.56667)
			(end -1.160272 -2.56667)
			(stroke
				(width 0.254)
				(type default)
			)
			(fill no)
			(layer "F.Fab")
		)
		(pad "1" smd rect
			(at -0.750062 -1.7145)
			(size 0.2794 0.8382)
			(layers "F.Cu" "F.Mask" "F.Paste")
			(net "VR_P5V_STBY_RT")
		)
		(pad "2" smd rect
			(at -1.7145 -0.999998)
			(size 0.8382 0.2794)
			(layers "F.Cu" "F.Mask" "F.Paste")
			(net "GND")
		)
		(pad "3" smd rect
			(at -1.7145 -0.500126)
			(size 0.8382 0.2794)
			(layers "F.Cu" "F.Mask" "F.Paste")
			(net "GND")
		)
		(pad "4" smd rect
			(at -1.7145 0)
			(size 0.8382 0.2794)
			(layers "F.Cu" "F.Mask" "F.Paste")
			(net "VR_FET_SW_P5V_STBY_PVIN")
		)
		(pad "5" smd rect
			(at -1.7145 0.500126)
			(size 0.8382 0.2794)
			(layers "F.Cu" "F.Mask" "F.Paste")
			(net "VR_FET_SW_P5V_STBY_PVIN")
		)
		(pad "6" smd rect
			(at -1.7145 0.999998)
			(size 0.8382 0.2794)
			(layers "F.Cu" "F.Mask" "F.Paste")
			(net "VR_P5V_STBY_VIN")
		)
		(pad "7" smd rect
			(at -0.750062 1.7145)
			(size 0.2794 0.8382)
			(layers "F.Cu" "F.Mask" "F.Paste")
			(net "VR_P5V_STBY_VSENSE")
		)
		(pad "8" smd rect
			(at 0.750062 1.7145)
			(size 0.2794 0.8382)
			(layers "F.Cu" "F.Mask" "F.Paste")
			(net "VR_P5V_STBY_COMP")
		)
		(pad "9" smd rect
			(at 1.7145 0.999998)
			(size 0.8382 0.2794)
			(layers "F.Cu" "F.Mask" "F.Paste")
			(net "VR_P5V_STBY_SS")
		)
		(pad "10" smd rect
			(at 1.7145 0.500126)
			(size 0.8382 0.2794)
			(layers "F.Cu" "F.Mask" "F.Paste")
			(net "VR_P5V_STBY_EN")
		)
		(pad "11" smd rect
			(at 1.7145 0)
			(size 0.8382 0.2794)
			(layers "F.Cu" "F.Mask" "F.Paste")
			(net "VR_P5V_STBY_PHASE")
		)
		(pad "12" smd rect
			(at 1.7145 -0.500126)
			(size 0.8382 0.2794)
			(layers "F.Cu" "F.Mask" "F.Paste")
			(net "VR_P5V_STBY_PHASE")
		)
		(pad "13" smd rect
			(at 1.7145 -0.999998)
			(size 0.8382 0.2794)
			(layers "F.Cu" "F.Mask" "F.Paste")
			(net "VR_P5V_STBY_BOOT")
		)
		(pad "14" smd rect
			(at 0.750062 -1.7145)
			(size 0.2794 0.8382)
			(layers "F.Cu" "F.Mask" "F.Paste")
			(net "PWRGD_P5V_STBY_R")
		)
		(pad "15" smd custom
			(at 0 0)
			(size 0.51435 0.51435)
			(layers "F.Cu" "F.Mask" "F.Paste")
			(net "GND")
			(options
				(clearance outline)
				(anchor circle)
			)
			(primitives
				(gr_poly
					(pts
						(xy -0.381 -2.1336) (xy -0.381 -1.0287) (xy -1.0287 -1.0287) (xy -1.0287 1.0287) (xy -0.381 1.0287)
						(xy -0.381 2.1336) (xy -0.1905 2.1336) (xy -0.1905 1.397) (xy 0.1905 1.397) (xy 0.1905 2.1336)
						(xy 0.381 2.1336) (xy 0.381 1.0287) (xy 1.0287 1.0287) (xy 1.0287 -1.0287) (xy 0.381 -1.0287)
						(xy 0.381 -2.1336) (xy 0.1905 -2.1336) (xy 0.1905 -1.397) (xy -0.1905 -1.397) (xy -0.1905 -2.1336)
					)
					(width 0)
					(fill yes)
				)
			)
		)
	)
)
